(kicad_pcb
	(version 20260206)
	(generator "pcbnew")
	(generator_version "10.0")
	(general
		(thickness 1.6)
		(legacy_teardrops no)
	)
	(paper "A4")
	(title_block
		(title "pdpb — Lightning_PDPB_BRD.brd")
		(comment 1 "Lightning (Wiwynn / Facebook NVMe JBOF) / footprints 154-156 of 1140")
	)
	(layers
		(0 "F.Cu" signal "TOP")
		(4 "In1.Cu" signal "L2GND")
		(6 "In2.Cu" signal "L3")
		(8 "In3.Cu" signal "L4VCC")
		(10 "In4.Cu" signal "L5VCC")
		(12 "In5.Cu" signal "L6")
		(14 "In6.Cu" signal "L7GND")
		(2 "B.Cu" signal "BOTTOM")
		(9 "F.Adhes" user "F.Adhesive")
		(11 "B.Adhes" user "B.Adhesive")
		(13 "F.Paste" user "Package Geometry/Pastemask Top")
		(15 "B.Paste" user "Package Geometry/Pastemask Bottom")
		(5 "F.SilkS" user "Ref Des/Silkscreen Top")
		(7 "B.SilkS" user "Ref Des/Silkscreen Bottom")
		(1 "F.Mask" user "Board Geometry/Soldermask Top")
		(3 "B.Mask" user "Board Geometry/Soldermask Bottom")
		(17 "Dwgs.User" user "User.Drawings")
		(19 "Cmts.User" user "User.Comments")
		(21 "Eco1.User" user "User.Eco1")
		(23 "Eco2.User" user "User.Eco2")
		(25 "Edge.Cuts" user "Board Geometry/Outline")
		(27 "Margin" user)
		(31 "F.CrtYd" user "Package Geometry/Place Bound Top")
		(29 "B.CrtYd" user "Package Geometry/Place Bound Bottom")
		(35 "F.Fab" user "Ref Des/Assembly Top")
		(33 "B.Fab" user "Ref Des/Assembly Bottom")
	)
	(footprint ""
		(layer "F.Cu")
		(at 86.487 -219.456 180)
		(property "Reference" "R9089"
			(at 0 0 180)
			(layer "F.SilkS")
			(hide yes)
			(effects
				(font
					(size 1.27 1.27)
				)
			)
		)
		(property "Value" "27R2F-GP"
			(at 0.064008 -3.993896 180)
			(unlocked yes)
			(layer "F.Fab")
			(hide yes)
			(effects
				(font
					(size 1.016 1.016)
					(thickness 0.1524)
				)
			)
		)
		(property "Device Type" "R402H16"
			(at 0.064008 -5.517896 180)
			(unlocked yes)
			(layer "F.Fab")
			(hide yes)
			(effects
				(font
					(size 1.016 1.016)
					(thickness 0.1524)
				)
			)
		)
		(duplicate_pad_numbers_are_jumpers no)
		(fp_line
			(start 0.508 -0.9398)
			(end -0.508 -0.9398)
			(stroke
				(width 0.1524)
				(type default)
			)
			(layer "F.SilkS")
		)
		(fp_line
			(start -0.508 -0.9398)
			(end -0.508 0.9398)
			(stroke
				(width 0.1524)
				(type default)
			)
			(layer "F.SilkS")
		)
		(fp_rect
			(start -0.508 0.9398)
			(end 0.508 -0.9398)
			(stroke
				(width 0)
				(type default)
			)
			(fill no)
			(layer "F.CrtYd")
		)
		(fp_rect
			(start -0.508 0.9398)
			(end 0.508 -0.9398)
			(stroke
				(width 0)
				(type default)
			)
			(fill no)
			(layer "F.Fab")
		)
		(pad "1" smd custom
			(at 0 -0.4445 180)
			(size 0.1397 0.1397)
			(layers "F.Cu" "F.Mask" "F.Paste")
			(net "PE_CLK_100M_DR12_1_R_N")
			(options
				(clearance outline)
				(anchor circle)
			)
			(primitives
				(gr_poly
					(pts
						(arc
							(start -0.1778 -0.2794)
							(mid -0.249642 -0.249642)
							(end -0.2794 -0.1778)
						)
						(arc
							(start -0.2794 0.1778)
							(mid -0.249642 0.249642)
							(end -0.1778 0.2794)
						)
						(arc
							(start 0.1778 0.2794)
							(mid 0.249642 0.249642)
							(end 0.2794 0.1778)
						)
						(arc
							(start 0.2794 -0.1778)
							(mid 0.249642 -0.249642)
							(end 0.1778 -0.2794)
						)
					)
					(width 0)
					(fill yes)
				)
			)
		)
		(pad "2" smd custom
			(at 0 0.4445 180)
			(size 0.1397 0.1397)
			(layers "F.Cu" "F.Mask" "F.Paste")
			(net "PE_CLK100M_DR12_1_N")
			(options
				(clearance outline)
				(anchor circle)
			)
			(primitives
				(gr_poly
					(pts
						(arc
							(start -0.1778 -0.2794)
							(mid -0.249642 -0.249642)
							(end -0.2794 -0.1778)
						)
						(arc
							(start -0.2794 0.1778)
							(mid -0.249642 0.249642)
							(end -0.1778 0.2794)
						)
						(arc
							(start 0.1778 0.2794)
							(mid 0.249642 0.249642)
							(end 0.2794 0.1778)
						)
						(arc
							(start 0.2794 -0.1778)
							(mid 0.249642 -0.249642)
							(end 0.1778 -0.2794)
						)
					)
					(width 0)
					(fill yes)
				)
			)
		)
	)
	(footprint ""
		(layer "F.Cu")
		(at 62.6364 -449.5546 -90)
		(property "Reference" "SR1131"
			(at 0 0 270)
			(layer "F.SilkS")
			(hide yes)
			(effects
				(font
					(size 1.27 1.27)
				)
			)
		)
		(property "Value" "4K7R2F-GP"
			(at 0.064008 -3.993896 270)
			(unlocked yes)
			(layer "F.Fab")
			(hide yes)
			(effects
				(font
					(size 1.016 1.016)
					(thickness 0.1524)
				)
			)
		)
		(property "Device Type" "R402H16"
			(at 0.064008 -5.517896 270)
			(unlocked yes)
			(layer "F.Fab")
			(hide yes)
			(effects
				(font
					(size 1.016 1.016)
					(thickness 0.1524)
				)
			)
		)
		(duplicate_pad_numbers_are_jumpers no)
		(fp_line
			(start -0.508 -0.9398)
			(end -0.508 0.9398)
			(stroke
				(width 0.1524)
				(type default)
			)
			(layer "F.SilkS")
		)
		(fp_line
			(start 0.508 -0.9398)
			(end -0.508 -0.9398)
			(stroke
				(width 0.1524)
				(type default)
			)
			(layer "F.SilkS")
		)
		(fp_rect
			(start -0.508 0.9398)
			(end 0.508 -0.9398)
			(stroke
				(width 0)
				(type default)
			)
			(fill no)
			(layer "F.CrtYd")
		)
		(fp_rect
			(start -0.508 0.9398)
			(end 0.508 -0.9398)
			(stroke
				(width 0)
				(type default)
			)
			(fill no)
			(layer "F.Fab")
		)
		(pad "1" smd custom
			(at 0 -0.4445 270)
			(size 0.1397 0.1397)
			(layers "F.Cu" "F.Mask" "F.Paste")
			(net "P3V3")
			(options
				(clearance outline)
				(anchor circle)
			)
			(primitives
				(gr_poly
					(pts
						(arc
							(start -0.1778 -0.2794)
							(mid -0.249642 -0.249642)
							(end -0.2794 -0.1778)
						)
						(arc
							(start -0.2794 0.1778)
							(mid -0.249642 0.249642)
							(end -0.1778 0.2794)
						)
						(arc
							(start 0.1778 0.2794)
							(mid 0.249642 0.249642)
							(end 0.2794 0.1778)
						)
						(arc
							(start 0.2794 -0.1778)
							(mid 0.249642 -0.249642)
							(end 0.1778 -0.2794)
						)
					)
					(width 0)
					(fill yes)
				)
			)
		)
		(pad "2" smd custom
			(at 0 0.4445 270)
			(size 0.1397 0.1397)
			(layers "F.Cu" "F.Mask" "F.Paste")
			(net "SSD5_CLK0_OE_MOS_N")
			(options
				(clearance outline)
				(anchor circle)
			)
			(primitives
				(gr_poly
					(pts
						(arc
							(start -0.1778 -0.2794)
							(mid -0.249642 -0.249642)
							(end -0.2794 -0.1778)
						)
						(arc
							(start -0.2794 0.1778)
							(mid -0.249642 0.249642)
							(end -0.1778 0.2794)
						)
						(arc
							(start 0.1778 0.2794)
							(mid 0.249642 0.249642)
							(end 0.2794 0.1778)
						)
						(arc
							(start 0.2794 -0.1778)
							(mid 0.249642 -0.249642)
							(end 0.1778 -0.2794)
						)
					)
					(width 0)
					(fill yes)
				)
			)
		)
	)
	(footprint ""
		(layer "F.Cu")
		(at 214.5284 -290.5506)
		(property "Reference" "SR1095"
			(at 0 0 0)
			(layer "F.SilkS")
			(hide yes)
			(effects
				(font
					(size 1.27 1.27)
				)
			)
		)
		(property "Value" "4K7R2F-GP"
			(at 0.064008 -3.993896 0)
			(unlocked yes)
			(layer "F.Fab")
			(hide yes)
			(effects
				(font
					(size 1.016 1.016)
					(thickness 0.1524)
				)
			)
		)
		(property "Device Type" "R402H16"
			(at 0.064008 -5.517896 0)
			(unlocked yes)
			(layer "F.Fab")
			(hide yes)
			(effects
				(font
					(size 1.016 1.016)
					(thickness 0.1524)
				)
			)
		)
		(duplicate_pad_numbers_are_jumpers no)
		(fp_line
			(start -0.508 -0.9398)
			(end -0.508 0.9398)
			(stroke
				(width 0.1524)
				(type default)
			)
			(layer "F.SilkS")
		)
		(fp_line
			(start 0.508 -0.9398)
			(end -0.508 -0.9398)
			(stroke
				(width 0.1524)
				(type default)
			)
			(layer "F.SilkS")
		)
		(fp_rect
			(start -0.508 0.9398)
			(end 0.508 -0.9398)
			(stroke
				(width 0)
				(type default)
			)
			(fill no)
			(layer "F.CrtYd")
		)
		(fp_rect
			(start -0.508 0.9398)
			(end 0.508 -0.9398)
			(stroke
				(width 0)
				(type default)
			)
			(fill no)
			(layer "F.Fab")
		)
		(pad "1" smd custom
			(at 0 -0.4445)
			(size 0.1397 0.1397)
			(layers "F.Cu" "F.Mask" "F.Paste")
			(net "P3V3")
			(options
				(clearance outline)
				(anchor circle)
			)
			(primitives
				(gr_poly
					(pts
						(arc
							(start -0.1778 -0.2794)
							(mid -0.249642 -0.249642)
							(end -0.2794 -0.1778)
						)
						(arc
							(start -0.2794 0.1778)
							(mid -0.249642 0.249642)
							(end -0.1778 0.2794)
						)
						(arc
							(start 0.1778 0.2794)
							(mid 0.249642 0.249642)
							(end 0.2794 0.1778)
						)
						(arc
							(start 0.2794 -0.1778)
							(mid 0.249642 -0.249642)
							(end 0.1778 -0.2794)
						)
					)
					(width 0)
					(fill yes)
				)
			)
		)
		(pad "2" smd custom
			(at 0 0.4445)
			(size 0.1397 0.1397)
			(layers "F.Cu" "F.Mask" "F.Paste")
			(net "DUALPORTEN#2")
			(options
				(clearance outline)
				(anchor circle)
			)
			(primitives
				(gr_poly
					(pts
						(arc
							(start -0.1778 -0.2794)
							(mid -0.249642 -0.249642)
							(end -0.2794 -0.1778)
						)
						(arc
							(start -0.2794 0.1778)
							(mid -0.249642 0.249642)
							(end -0.1778 0.2794)
						)
						(arc
							(start 0.1778 0.2794)
							(mid 0.249642 0.249642)
							(end 0.2794 0.1778)
						)
						(arc
							(start 0.2794 -0.1778)
							(mid 0.249642 -0.249642)
							(end 0.1778 -0.2794)
						)
					)
					(width 0)
					(fill yes)
				)
			)
		)
	)
)
